(kicad_pcb
	(version 20260206)
	(generator "pcbnew")
	(generator_version "10.0")
	(general
		(thickness 1.6)
		(legacy_teardrops no)
	)
	(paper "A4")
	(title_block
		(title "01162023_DA0F0TEBIF0_F0T_Expander_BD_F_brd_V02_OCP.brd")
		(comment 1 "Grand Teton / footprints 3351-3356 of 9728")
	)
	(layers
		(0 "F.Cu" signal "TOP")
		(4 "In1.Cu" signal "GND")
		(6 "In2.Cu" signal "VCC")
		(8 "In3.Cu" signal "VCC1")
		(10 "In4.Cu" signal "GND1")
		(12 "In5.Cu" signal "IN1")
		(14 "In6.Cu" signal "GND2")
		(16 "In7.Cu" signal "IN2")
		(18 "In8.Cu" signal "GND3")
		(20 "In9.Cu" signal "IN3")
		(22 "In10.Cu" signal "GND4")
		(24 "In11.Cu" signal "IN4")
		(26 "In12.Cu" signal "GND5")
		(28 "In13.Cu" signal "IN5")
		(30 "In14.Cu" signal "GND6")
		(32 "In15.Cu" signal "IN6")
		(34 "In16.Cu" signal "GND7")
		(2 "B.Cu" signal "BOTTOM")
		(9 "F.Adhes" user "F.Adhesive")
		(11 "B.Adhes" user "B.Adhesive")
		(13 "F.Paste" user "Package Geometry/Pastemask Top")
		(15 "B.Paste" user "Package Geometry/Pastemask Bottom")
		(5 "F.SilkS" user "Ref Des/Silkscreen Top")
		(7 "B.SilkS" user "Ref Des/Silkscreen Bottom")
		(1 "F.Mask" user "Board Geometry/Soldermask Top")
		(3 "B.Mask" user "Board Geometry/Soldermask Bottom")
		(17 "Dwgs.User" user "User.Drawings")
		(19 "Cmts.User" user "User.Comments")
		(21 "Eco1.User" user "User.Eco1")
		(23 "Eco2.User" user "User.Eco2")
		(25 "Edge.Cuts" user "Board Geometry/Outline")
		(27 "Margin" user)
		(31 "F.CrtYd" user "Package Geometry/Place Bound Top")
		(29 "B.CrtYd" user "Package Geometry/Place Bound Bottom")
		(35 "F.Fab" user "Ref Des/Assembly Top")
		(33 "B.Fab" user "Ref Des/Assembly Bottom")
	)
	(footprint ""
		(layer "F.Cu")
		(at 9.62914 -310.00827 180)
		(property "Reference" "PC204"
			(at 0 0 180)
			(layer "F.SilkS")
			(hide yes)
			(effects
				(font
					(size 1.27 1.27)
				)
			)
		)
		(property "Value" ""
			(at 0 0 180)
			(layer "F.Fab")
			(effects
				(font
					(size 1.27 1.27)
				)
			)
		)
		(duplicate_pad_numbers_are_jumpers no)
		(fp_line
			(start 1.524 0.762)
			(end -1.524 0.762)
			(stroke
				(width 0.1524)
				(type default)
			)
			(layer "F.SilkS")
		)
		(fp_line
			(start 1.524 -0.762)
			(end 1.524 0.762)
			(stroke
				(width 0.1524)
				(type default)
			)
			(layer "F.SilkS")
		)
		(fp_line
			(start -1.524 0.762)
			(end -1.524 -0.762)
			(stroke
				(width 0.1524)
				(type default)
			)
			(layer "F.SilkS")
		)
		(fp_line
			(start -1.524 -0.762)
			(end 1.524 -0.762)
			(stroke
				(width 0.1524)
				(type default)
			)
			(layer "F.SilkS")
		)
		(fp_line
			(start 1.1049 0.724916)
			(end 1.1049 -0.724916)
			(stroke
				(width 0.1)
				(type default)
			)
			(layer "F.Fab")
		)
		(fp_line
			(start 1.1049 -0.724916)
			(end -1.1049 -0.724916)
			(stroke
				(width 0.1)
				(type default)
			)
			(layer "F.Fab")
		)
		(fp_line
			(start -1.1049 0.724916)
			(end 1.1049 0.724916)
			(stroke
				(width 0.1)
				(type default)
			)
			(layer "F.Fab")
		)
		(fp_line
			(start -1.1049 -0.724916)
			(end -1.1049 0.724916)
			(stroke
				(width 0.1)
				(type default)
			)
			(layer "F.Fab")
		)
		(pad "1" smd rect
			(at -0.889 0)
			(size 1.016 1.27)
			(layers "F.Cu" "F.Mask" "F.Paste")
			(net "SW_P12V_P1V25_PEX0_FLT")
		)
		(pad "2" smd rect
			(at 0.889 0)
			(size 1.016 1.27)
			(layers "F.Cu" "F.Mask" "F.Paste")
			(net "GND")
		)
	)
	(footprint ""
		(layer "F.Cu")
		(at 342.646 -205.232 -90)
		(property "Reference" "R4138"
			(at 0 0 270)
			(layer "F.SilkS")
			(hide yes)
			(effects
				(font
					(size 1.27 1.27)
				)
			)
		)
		(property "Value" ""
			(at 0 0 270)
			(layer "F.Fab")
			(effects
				(font
					(size 1.27 1.27)
				)
			)
		)
		(duplicate_pad_numbers_are_jumpers no)
		(fp_line
			(start -0.7874 0.4064)
			(end -0.7874 -0.4064)
			(stroke
				(width 0.1524)
				(type default)
			)
			(layer "F.SilkS")
		)
		(fp_line
			(start 0.7874 0.4064)
			(end -0.7874 0.4064)
			(stroke
				(width 0.1524)
				(type default)
			)
			(layer "F.SilkS")
		)
		(fp_line
			(start -0.7874 -0.4064)
			(end 0.7874 -0.4064)
			(stroke
				(width 0.1524)
				(type default)
			)
			(layer "F.SilkS")
		)
		(fp_line
			(start 0.7874 -0.4064)
			(end 0.7874 0.4064)
			(stroke
				(width 0.1524)
				(type default)
			)
			(layer "F.SilkS")
		)
		(fp_line
			(start -0.67945 0.3048)
			(end -0.67945 -0.305054)
			(stroke
				(width 0.1)
				(type default)
			)
			(layer "F.Fab")
		)
		(fp_line
			(start -0.12065 0.3048)
			(end -0.67945 0.3048)
			(stroke
				(width 0.1)
				(type default)
			)
			(layer "F.Fab")
		)
		(fp_line
			(start 0.120396 0.3048)
			(end 0.120396 0.2794)
			(stroke
				(width 0.1)
				(type default)
			)
			(layer "F.Fab")
		)
		(fp_line
			(start 0.67945 0.3048)
			(end 0.120396 0.3048)
			(stroke
				(width 0.1)
				(type default)
			)
			(layer "F.Fab")
		)
		(fp_line
			(start -0.12065 0.2794)
			(end -0.12065 0.3048)
			(stroke
				(width 0.1)
				(type default)
			)
			(layer "F.Fab")
		)
		(fp_line
			(start 0.120396 0.2794)
			(end -0.12065 0.2794)
			(stroke
				(width 0.1)
				(type default)
			)
			(layer "F.Fab")
		)
		(fp_line
			(start -0.12065 -0.2794)
			(end 0.12065 -0.2794)
			(stroke
				(width 0.1)
				(type default)
			)
			(layer "F.Fab")
		)
		(fp_line
			(start 0.12065 -0.2794)
			(end 0.12065 -0.3048)
			(stroke
				(width 0.1)
				(type default)
			)
			(layer "F.Fab")
		)
		(fp_line
			(start 0.12065 -0.3048)
			(end 0.67945 -0.3048)
			(stroke
				(width 0.1)
				(type default)
			)
			(layer "F.Fab")
		)
		(fp_line
			(start 0.67945 -0.3048)
			(end 0.67945 0.3048)
			(stroke
				(width 0.1)
				(type default)
			)
			(layer "F.Fab")
		)
		(fp_line
			(start -0.67945 -0.305054)
			(end -0.12065 -0.305054)
			(stroke
				(width 0.1)
				(type default)
			)
			(layer "F.Fab")
		)
		(fp_line
			(start -0.12065 -0.305054)
			(end -0.12065 -0.2794)
			(stroke
				(width 0.1)
				(type default)
			)
			(layer "F.Fab")
		)
		(pad "1" smd circle
			(at -0.40005 0 270)
			(size 0 0)
			(layers "F.Cu" "F.Mask" "F.Paste")
			(net "SSD13_CLK_EN_N")
		)
		(pad "2" smd circle
			(at 0.40005 0 270)
			(size 0 0)
			(layers "F.Cu" "F.Mask" "F.Paste")
			(net "SSD13_CLK_EN_R_N")
		)
	)
	(footprint ""
		(layer "F.Cu")
		(at 93.066108 -306.074572 90)
		(property "Reference" "R4179"
			(at 0 0 90)
			(layer "F.SilkS")
			(hide yes)
			(effects
				(font
					(size 1.27 1.27)
				)
			)
		)
		(property "Value" ""
			(at 0 0 90)
			(layer "F.Fab")
			(effects
				(font
					(size 1.27 1.27)
				)
			)
		)
		(duplicate_pad_numbers_are_jumpers no)
		(fp_line
			(start 0.7874 -0.4064)
			(end 0.7874 0.4064)
			(stroke
				(width 0.1524)
				(type default)
			)
			(layer "F.SilkS")
		)
		(fp_line
			(start -0.7874 -0.4064)
			(end 0.7874 -0.4064)
			(stroke
				(width 0.1524)
				(type default)
			)
			(layer "F.SilkS")
		)
		(fp_line
			(start 0.7874 0.4064)
			(end -0.7874 0.4064)
			(stroke
				(width 0.1524)
				(type default)
			)
			(layer "F.SilkS")
		)
		(fp_line
			(start -0.7874 0.4064)
			(end -0.7874 -0.4064)
			(stroke
				(width 0.1524)
				(type default)
			)
			(layer "F.SilkS")
		)
		(fp_line
			(start -0.12065 -0.305054)
			(end -0.12065 -0.2794)
			(stroke
				(width 0.1)
				(type default)
			)
			(layer "F.Fab")
		)
		(fp_line
			(start -0.67945 -0.305054)
			(end -0.12065 -0.305054)
			(stroke
				(width 0.1)
				(type default)
			)
			(layer "F.Fab")
		)
		(fp_line
			(start 0.67945 -0.3048)
			(end 0.67945 0.3048)
			(stroke
				(width 0.1)
				(type default)
			)
			(layer "F.Fab")
		)
		(fp_line
			(start 0.12065 -0.3048)
			(end 0.67945 -0.3048)
			(stroke
				(width 0.1)
				(type default)
			)
			(layer "F.Fab")
		)
		(fp_line
			(start 0.12065 -0.2794)
			(end 0.12065 -0.3048)
			(stroke
				(width 0.1)
				(type default)
			)
			(layer "F.Fab")
		)
		(fp_line
			(start -0.12065 -0.2794)
			(end 0.12065 -0.2794)
			(stroke
				(width 0.1)
				(type default)
			)
			(layer "F.Fab")
		)
		(fp_line
			(start 0.120396 0.2794)
			(end -0.12065 0.2794)
			(stroke
				(width 0.1)
				(type default)
			)
			(layer "F.Fab")
		)
		(fp_line
			(start -0.12065 0.2794)
			(end -0.12065 0.3048)
			(stroke
				(width 0.1)
				(type default)
			)
			(layer "F.Fab")
		)
		(fp_line
			(start 0.67945 0.3048)
			(end 0.120396 0.3048)
			(stroke
				(width 0.1)
				(type default)
			)
			(layer "F.Fab")
		)
		(fp_line
			(start 0.120396 0.3048)
			(end 0.120396 0.2794)
			(stroke
				(width 0.1)
				(type default)
			)
			(layer "F.Fab")
		)
		(fp_line
			(start -0.12065 0.3048)
			(end -0.67945 0.3048)
			(stroke
				(width 0.1)
				(type default)
			)
			(layer "F.Fab")
		)
		(fp_line
			(start -0.67945 0.3048)
			(end -0.67945 -0.305054)
			(stroke
				(width 0.1)
				(type default)
			)
			(layer "F.Fab")
		)
		(pad "1" smd circle
			(at -0.40005 0 90)
			(size 0 0)
			(layers "F.Cu" "F.Mask" "F.Paste")
			(net "PEX0_EXT_GPIO_LATCH_N")
		)
		(pad "2" smd circle
			(at 0.40005 0 90)
			(size 0 0)
			(layers "F.Cu" "F.Mask" "F.Paste")
			(net "P1V8_PEX")
		)
	)
	(footprint ""
		(layer "F.Cu")
		(at 436.588154 -100.459032 90)
		(property "Reference" "R766"
			(at 0 0 90)
			(layer "F.SilkS")
			(hide yes)
			(effects
				(font
					(size 1.27 1.27)
				)
			)
		)
		(property "Value" ""
			(at 0 0 90)
			(layer "F.Fab")
			(effects
				(font
					(size 1.27 1.27)
				)
			)
		)
		(duplicate_pad_numbers_are_jumpers no)
		(fp_line
			(start 0.7874 -0.4064)
			(end 0.7874 0.4064)
			(stroke
				(width 0.1524)
				(type default)
			)
			(layer "F.SilkS")
		)
		(fp_line
			(start -0.7874 -0.4064)
			(end 0.7874 -0.4064)
			(stroke
				(width 0.1524)
				(type default)
			)
			(layer "F.SilkS")
		)
		(fp_line
			(start 0.7874 0.4064)
			(end -0.7874 0.4064)
			(stroke
				(width 0.1524)
				(type default)
			)
			(layer "F.SilkS")
		)
		(fp_line
			(start -0.7874 0.4064)
			(end -0.7874 -0.4064)
			(stroke
				(width 0.1524)
				(type default)
			)
			(layer "F.SilkS")
		)
		(fp_line
			(start -0.12065 -0.305054)
			(end -0.12065 -0.2794)
			(stroke
				(width 0.1)
				(type default)
			)
			(layer "F.Fab")
		)
		(fp_line
			(start -0.67945 -0.305054)
			(end -0.12065 -0.305054)
			(stroke
				(width 0.1)
				(type default)
			)
			(layer "F.Fab")
		)
		(fp_line
			(start 0.67945 -0.3048)
			(end 0.67945 0.3048)
			(stroke
				(width 0.1)
				(type default)
			)
			(layer "F.Fab")
		)
		(fp_line
			(start 0.12065 -0.3048)
			(end 0.67945 -0.3048)
			(stroke
				(width 0.1)
				(type default)
			)
			(layer "F.Fab")
		)
		(fp_line
			(start 0.12065 -0.2794)
			(end 0.12065 -0.3048)
			(stroke
				(width 0.1)
				(type default)
			)
			(layer "F.Fab")
		)
		(fp_line
			(start -0.12065 -0.2794)
			(end 0.12065 -0.2794)
			(stroke
				(width 0.1)
				(type default)
			)
			(layer "F.Fab")
		)
		(fp_line
			(start 0.120396 0.2794)
			(end -0.12065 0.2794)
			(stroke
				(width 0.1)
				(type default)
			)
			(layer "F.Fab")
		)
		(fp_line
			(start -0.12065 0.2794)
			(end -0.12065 0.3048)
			(stroke
				(width 0.1)
				(type default)
			)
			(layer "F.Fab")
		)
		(fp_line
			(start 0.67945 0.3048)
			(end 0.120396 0.3048)
			(stroke
				(width 0.1)
				(type default)
			)
			(layer "F.Fab")
		)
		(fp_line
			(start 0.120396 0.3048)
			(end 0.120396 0.2794)
			(stroke
				(width 0.1)
				(type default)
			)
			(layer "F.Fab")
		)
		(fp_line
			(start -0.12065 0.3048)
			(end -0.67945 0.3048)
			(stroke
				(width 0.1)
				(type default)
			)
			(layer "F.Fab")
		)
		(fp_line
			(start -0.67945 0.3048)
			(end -0.67945 -0.305054)
			(stroke
				(width 0.1)
				(type default)
			)
			(layer "F.Fab")
		)
		(pad "1" smd circle
			(at -0.40005 0 90)
			(size 0 0)
			(layers "F.Cu" "F.Mask" "F.Paste")
			(net "P12V_NIC7_R")
		)
		(pad "2" smd circle
			(at 0.40005 0 90)
			(size 0 0)
			(layers "F.Cu" "F.Mask" "F.Paste")
			(net "P12V_NIC7_VIN_P")
		)
	)
	(footprint ""
		(layer "F.Cu")
		(at 338.074 -145.923 180)
		(property "Reference" "R4833"
			(at 0 0 180)
			(layer "F.SilkS")
			(hide yes)
			(effects
				(font
					(size 1.27 1.27)
				)
			)
		)
		(property "Value" ""
			(at 0 0 180)
			(layer "F.Fab")
			(effects
				(font
					(size 1.27 1.27)
				)
			)
		)
		(duplicate_pad_numbers_are_jumpers no)
		(fp_line
			(start 0.7874 0.4064)
			(end -0.7874 0.4064)
			(stroke
				(width 0.1524)
				(type default)
			)
			(layer "F.SilkS")
		)
		(fp_line
			(start 0.7874 -0.4064)
			(end 0.7874 0.4064)
			(stroke
				(width 0.1524)
				(type default)
			)
			(layer "F.SilkS")
		)
		(fp_line
			(start -0.7874 0.4064)
			(end -0.7874 -0.4064)
			(stroke
				(width 0.1524)
				(type default)
			)
			(layer "F.SilkS")
		)
		(fp_line
			(start -0.7874 -0.4064)
			(end 0.7874 -0.4064)
			(stroke
				(width 0.1524)
				(type default)
			)
			(layer "F.SilkS")
		)
		(fp_line
			(start 0.67945 0.3048)
			(end 0.120396 0.3048)
			(stroke
				(width 0.1)
				(type default)
			)
			(layer "F.Fab")
		)
		(fp_line
			(start 0.67945 -0.3048)
			(end 0.67945 0.3048)
			(stroke
				(width 0.1)
				(type default)
			)
			(layer "F.Fab")
		)
		(fp_line
			(start 0.12065 -0.2794)
			(end 0.12065 -0.3048)
			(stroke
				(width 0.1)
				(type default)
			)
			(layer "F.Fab")
		)
		(fp_line
			(start 0.12065 -0.3048)
			(end 0.67945 -0.3048)
			(stroke
				(width 0.1)
				(type default)
			)
			(layer "F.Fab")
		)
		(fp_line
			(start 0.120396 0.3048)
			(end 0.120396 0.2794)
			(stroke
				(width 0.1)
				(type default)
			)
			(layer "F.Fab")
		)
		(fp_line
			(start 0.120396 0.2794)
			(end -0.12065 0.2794)
			(stroke
				(width 0.1)
				(type default)
			)
			(layer "F.Fab")
		)
		(fp_line
			(start -0.12065 0.3048)
			(end -0.67945 0.3048)
			(stroke
				(width 0.1)
				(type default)
			)
			(layer "F.Fab")
		)
		(fp_line
			(start -0.12065 0.2794)
			(end -0.12065 0.3048)
			(stroke
				(width 0.1)
				(type default)
			)
			(layer "F.Fab")
		)
		(fp_line
			(start -0.12065 -0.2794)
			(end 0.12065 -0.2794)
			(stroke
				(width 0.1)
				(type default)
			)
			(layer "F.Fab")
		)
		(fp_line
			(start -0.12065 -0.305054)
			(end -0.12065 -0.2794)
			(stroke
				(width 0.1)
				(type default)
			)
			(layer "F.Fab")
		)
		(fp_line
			(start -0.67945 0.3048)
			(end -0.67945 -0.305054)
			(stroke
				(width 0.1)
				(type default)
			)
			(layer "F.Fab")
		)
		(fp_line
			(start -0.67945 -0.305054)
			(end -0.12065 -0.305054)
			(stroke
				(width 0.1)
				(type default)
			)
			(layer "F.Fab")
		)
		(pad "1" smd circle
			(at -0.40005 0 180)
			(size 0 0)
			(layers "F.Cu" "F.Mask" "F.Paste")
			(net "RST_PEX_SSD14_PERST_N")
		)
		(pad "2" smd circle
			(at 0.40005 0 180)
			(size 0 0)
			(layers "F.Cu" "F.Mask" "F.Paste")
			(net "RST_PEX_SSD14_PERST_R_N")
		)
	)
	(footprint ""
		(layer "F.Cu")
		(at 239.378998 -93.01607 -90)
		(property "Reference" "C2623"
			(at 0 0 270)
			(layer "F.SilkS")
			(hide yes)
			(effects
				(font
					(size 1.27 1.27)
				)
			)
		)
		(property "Value" ""
			(at 0 0 270)
			(layer "F.Fab")
			(effects
				(font
					(size 1.27 1.27)
				)
			)
		)
		(duplicate_pad_numbers_are_jumpers no)
		(fp_line
			(start -0.7874 0.4064)
			(end -0.7874 -0.4064)
			(stroke
				(width 0.1524)
				(type default)
			)
			(layer "F.SilkS")
		)
		(fp_line
			(start 0.7874 0.4064)
			(end -0.7874 0.4064)
			(stroke
				(width 0.1524)
				(type default)
			)
			(layer "F.SilkS")
		)
		(fp_line
			(start -0.7874 -0.4064)
			(end 0.7874 -0.4064)
			(stroke
				(width 0.1524)
				(type default)
			)
			(layer "F.SilkS")
		)
		(fp_line
			(start 0.7874 -0.4064)
			(end 0.7874 0.4064)
			(stroke
				(width 0.1524)
				(type default)
			)
			(layer "F.SilkS")
		)
		(fp_line
			(start -0.67945 0.3048)
			(end -0.67945 -0.305054)
			(stroke
				(width 0.1)
				(type default)
			)
			(layer "F.Fab")
		)
		(fp_line
			(start -0.12065 0.3048)
			(end -0.67945 0.3048)
			(stroke
				(width 0.1)
				(type default)
			)
			(layer "F.Fab")
		)
		(fp_line
			(start 0.120396 0.3048)
			(end 0.120396 0.2794)
			(stroke
				(width 0.1)
				(type default)
			)
			(layer "F.Fab")
		)
		(fp_line
			(start 0.67945 0.3048)
			(end 0.120396 0.3048)
			(stroke
				(width 0.1)
				(type default)
			)
			(layer "F.Fab")
		)
		(fp_line
			(start -0.12065 0.2794)
			(end -0.12065 0.3048)
			(stroke
				(width 0.1)
				(type default)
			)
			(layer "F.Fab")
		)
		(fp_line
			(start 0.120396 0.2794)
			(end -0.12065 0.2794)
			(stroke
				(width 0.1)
				(type default)
			)
			(layer "F.Fab")
		)
		(fp_line
			(start -0.12065 -0.2794)
			(end 0.12065 -0.2794)
			(stroke
				(width 0.1)
				(type default)
			)
			(layer "F.Fab")
		)
		(fp_line
			(start 0.12065 -0.2794)
			(end 0.12065 -0.3048)
			(stroke
				(width 0.1)
				(type default)
			)
			(layer "F.Fab")
		)
		(fp_line
			(start 0.12065 -0.3048)
			(end 0.67945 -0.3048)
			(stroke
				(width 0.1)
				(type default)
			)
			(layer "F.Fab")
		)
		(fp_line
			(start 0.67945 -0.3048)
			(end 0.67945 0.3048)
			(stroke
				(width 0.1)
				(type default)
			)
			(layer "F.Fab")
		)
		(fp_line
			(start -0.67945 -0.305054)
			(end -0.12065 -0.305054)
			(stroke
				(width 0.1)
				(type default)
			)
			(layer "F.Fab")
		)
		(fp_line
			(start -0.12065 -0.305054)
			(end -0.12065 -0.2794)
			(stroke
				(width 0.1)
				(type default)
			)
			(layer "F.Fab")
		)
		(pad "1" smd circle
			(at -0.40005 0 270)
			(size 0 0)
			(layers "F.Cu" "F.Mask" "F.Paste")
			(net "PEX_USB_HUB_XOUT_R")
		)
		(pad "2" smd circle
			(at 0.40005 0 270)
			(size 0 0)
			(layers "F.Cu" "F.Mask" "F.Paste")
			(net "GND")
		)
	)
)
